(kicad_pcb
	(version 20221018)
	(generator pcbnew)
	(general
    (thickness 1.6)
  )
	(paper "A4")
	(title_block
    (title "NUC Computer Cluster Power Breakout HW")
    (date "2023-10-18")
    (rev "1.4.3")
    (company "Antmicro Ltd.")
		(comment 9 "footprints 184-191 of 234")
	)
	(layers
    (0 "F.Cu" mixed)
    (1 "In1.Cu" power)
    (2 "In2.Cu" mixed)
    (31 "B.Cu" power)
    (32 "B.Adhes" user "B.Adhesive")
    (33 "F.Adhes" user "F.Adhesive")
    (34 "B.Paste" user)
    (35 "F.Paste" user)
    (36 "B.SilkS" user "B.Silkscreen")
    (37 "F.SilkS" user "F.Silkscreen")
    (38 "B.Mask" user)
    (39 "F.Mask" user)
    (40 "Dwgs.User" user "User.Drawings")
    (41 "Cmts.User" user "User.Comments")
    (42 "Eco1.User" user "User.Eco1")
    (43 "Eco2.User" user "User.Eco2")
    (44 "Edge.Cuts" user)
    (45 "Margin" user)
    (46 "B.CrtYd" user "B.Courtyard")
    (47 "F.CrtYd" user "F.Courtyard")
    (48 "B.Fab" user)
    (49 "F.Fab" user)
  )
	(footprint "antmicro-footprints:R_0402_1005Metric" (layer "F.Cu")
    (at 163.9 99.085 90)
    (descr "Resistor SMD 0402")
    (tags "resistor SMD 0402")
    (property "Author" "Antmicro")
    (property "License" "Apache-2.0")
    (property "MPN" "CR0402-FX-4701GLF")
    (property "Manufacturer" "Bourns")
    (property "Sheetfile" "ftdi-module.kicad_sch")
    (property "Sheetname" "FTDI")
    (property "Tolerance" "1%")
    (property "Val" "4k7")
    (property "ki_description" "SMD Chip Resistor, 4.7 kohm, ± 1%, 62.5 mW, 0402 [1005 Metric], Thick Film, General Purpose")
    (property "ki_keywords" "0402, SMT, RESISTOR, PASSIVE")
    (attr smd)
    (fp_text reference "R36" (at -0.515 1.45 90) (layer "F.SilkS")
        (effects (font (size 0.7 0.7) (thickness 0.15)) (justify left bottom))
    )
    (fp_text value "R_4k7_0402" (at -1.011843 1.772047 90) (layer "F.Fab")
        (effects (font (size 0.7 0.7) (thickness 0.15)) (justify left bottom))
    )
    (fp_text user "Author: Antmicro" (at -0.95 4.169 90) (layer "F.Fab") hide
        (effects (font (size 0.7 0.7) (thickness 0.15)) (justify left bottom))
    )
    (fp_text user "License: Apache-2.0" (at -0.95 5.169 90) (layer "F.Fab") hide
        (effects (font (size 0.7 0.7) (thickness 0.15)) (justify left bottom))
    )
    (fp_text user "${REFERENCE}" (at -0.95 3.168 90) (layer "F.Fab") hide
        (effects (font (size 0.7 0.7) (thickness 0.15)) (justify left bottom))
    )
    (fp_rect (start -0.925 -0.47) (end 0.925 0.47)
      (stroke (width 0.05) (type default)) (fill none) (layer "F.CrtYd"))
    (fp_rect (start -0.5 -0.25) (end 0.5 0.25)
      (stroke (width 0.15) (type solid)) (fill none) (layer "F.Fab"))
    (pad "1" smd roundrect (at -0.48 0 90) (size 0.59 0.64) (layers "F.Cu" "F.Paste" "F.Mask") (roundrect_rratio 0.25)
      (net 17 "SCL") (pintype "passive"))
    (pad "2" smd roundrect (at 0.48 0 90) (size 0.59 0.64) (layers "F.Cu" "F.Paste" "F.Mask") (roundrect_rratio 0.25)
      (net 1 "VCC3V3") (pintype "passive"))
  )
	(footprint "antmicro-footprints:R_0402_1005Metric" (layer "F.Cu")
    (at 113.65 90.2 -90)
    (descr "Resistor SMD 0402")
    (tags "resistor SMD 0402")
    (property "Author" "Antmicro")
    (property "License" "Apache-2.0")
    (property "MPN" "CR0402-FX-2R00GLF")
    (property "Manufacturer" "Bourns")
    (property "Sheetfile" "power-switch.kicad_sch")
    (property "Sheetname" "Power switch 1")
    (property "Tolerance" "1%")
    (property "Val" "2R")
    (property "ki_description" "SMD Chip Resistor")
    (property "ki_keywords" "0402, SMT, RESISTOR, PASSIVE")
    (attr smd)
    (fp_text reference "R60" (at -0.15 0.75 90) (layer "F.SilkS")
        (effects (font (size 0.7 0.7) (thickness 0.15)) (justify right bottom))
    )
    (fp_text value "R_2R_0402" (at -1.011843 1.772047 90) (layer "F.Fab")
        (effects (font (size 0.7 0.7) (thickness 0.15)) (justify right bottom))
    )
    (fp_text user "${REFERENCE}" (at -0.95 3.168 90) (layer "F.Fab") hide
        (effects (font (size 0.7 0.7) (thickness 0.15)) (justify right bottom))
    )
    (fp_text user "License: Apache-2.0" (at -0.95 5.169 90) (layer "F.Fab") hide
        (effects (font (size 0.7 0.7) (thickness 0.15)) (justify right bottom))
    )
    (fp_text user "Author: Antmicro" (at -0.95 4.169 90) (layer "F.Fab") hide
        (effects (font (size 0.7 0.7) (thickness 0.15)) (justify right bottom))
    )
    (fp_rect (start -0.925 -0.47) (end 0.925 0.47)
      (stroke (width 0.05) (type default)) (fill none) (layer "F.CrtYd"))
    (fp_rect (start -0.5 -0.25) (end 0.5 0.25)
      (stroke (width 0.15) (type solid)) (fill none) (layer "F.Fab"))
    (pad "1" smd roundrect (at -0.48 0 270) (size 0.59 0.64) (layers "F.Cu" "F.Paste" "F.Mask") (roundrect_rratio 0.25)
      (net 98 "Net-(QB1-G)") (pintype "passive"))
    (pad "2" smd roundrect (at 0.48 0 270) (size 0.59 0.64) (layers "F.Cu" "F.Paste" "F.Mask") (roundrect_rratio 0.25)
      (net 83 "Net-(D15-A)") (pintype "passive"))
  )
	(footprint "antmicro-footprints:R_0402_1005Metric" (layer "F.Cu")
    (at 121.2 91.5 90)
    (descr "Resistor SMD 0402")
    (tags "resistor SMD 0402")
    (property "Author" "Antmicro")
    (property "License" "Apache-2.0")
    (property "MPN" "CR0402-FX-2R00GLF")
    (property "Manufacturer" "Bourns")
    (property "Sheetfile" "power-switch.kicad_sch")
    (property "Sheetname" "Power switch 1")
    (property "Tolerance" "1%")
    (property "Val" "2R")
    (property "ki_description" "SMD Chip Resistor")
    (property "ki_keywords" "0402, SMT, RESISTOR, PASSIVE")
    (attr smd)
    (fp_text reference "R62" (at -2.05 -0.6 90) (layer "F.SilkS")
        (effects (font (size 0.7 0.7) (thickness 0.15)) (justify left bottom))
    )
    (fp_text value "R_2R_0402" (at -1.011843 1.772047 90) (layer "F.Fab")
        (effects (font (size 0.7 0.7) (thickness 0.15)) (justify left bottom))
    )
    (fp_text user "License: Apache-2.0" (at -0.95 5.169 90) (layer "F.Fab") hide
        (effects (font (size 0.7 0.7) (thickness 0.15)) (justify left bottom))
    )
    (fp_text user "${REFERENCE}" (at -0.95 3.168 90) (layer "F.Fab") hide
        (effects (font (size 0.7 0.7) (thickness 0.15)) (justify left bottom))
    )
    (fp_text user "Author: Antmicro" (at -0.95 4.169 90) (layer "F.Fab") hide
        (effects (font (size 0.7 0.7) (thickness 0.15)) (justify left bottom))
    )
    (fp_rect (start -0.925 -0.47) (end 0.925 0.47)
      (stroke (width 0.05) (type default)) (fill none) (layer "F.CrtYd"))
    (fp_rect (start -0.5 -0.25) (end 0.5 0.25)
      (stroke (width 0.15) (type solid)) (fill none) (layer "F.Fab"))
    (pad "1" smd roundrect (at -0.48 0 90) (size 0.59 0.64) (layers "F.Cu" "F.Paste" "F.Mask") (roundrect_rratio 0.25)
      (net 83 "Net-(D15-A)") (pintype "passive"))
    (pad "2" smd roundrect (at 0.48 0 90) (size 0.59 0.64) (layers "F.Cu" "F.Paste" "F.Mask") (roundrect_rratio 0.25)
      (net 93 "Net-(QA1-G)") (pintype "passive"))
  )
	(footprint "antmicro-footprints:Vishay_PowerPAK_1212-8_Single" (layer "F.Cu")
    (at 154.1775 86.2275 90)
    (descr "PowerPAK 1212-8 Single")
    (tags "Vishay PowerPAK 1212-8 Single")
    (property "Author" "Antmicro")
    (property "License" "Apache-2.0")
    (property "MPN" "SI7613DN-T1-GE3")
    (property "Manufacturer" "Vishay")
    (property "Sheetfile" "power-switch.kicad_sch")
    (property "Sheetname" "Power switch 3")
    (property "ki_description" "Power MOSFET, P Channel, 20 V, 35 A, 0.0072 ohm, PowerPAK 1212, Surface Mount")
    (property "ki_keywords" "SMT, TRANSISTOR, SEMICONDUCTOR, MOSFET, PMOS")
    (attr smd)
    (fp_text reference "QB3" (at -3.0225 0.2225 180) (layer "F.SilkS")
        (effects (font (size 0.7 0.7) (thickness 0.15)) (justify left bottom))
    )
    (fp_text value "SI7613DN-T1-GE3" (at 0 2.7 90) (layer "F.Fab")
        (effects (font (size 0.7 0.7) (thickness 0.15)) (justify left bottom))
    )
    (fp_text user "${REFERENCE}" (at -8 4.7 90) (layer "F.Fab") hide
        (effects (font (size 0.7 0.7) (thickness 0.15)) (justify left bottom))
    )
    (fp_text user "Author: Antmicro" (at -8 5.9 90) (layer "F.Fab") hide
        (effects (font (size 0.7 0.7) (thickness 0.15)) (justify left bottom))
    )
    (fp_text user "License: Apache-2.0" (at -8 7.1 90) (layer "F.Fab") hide
        (effects (font (size 0.7 0.7) (thickness 0.15)) (justify left bottom))
    )
    (fp_line (start -1.651 -1.651) (end -1.651 -1.317)
      (stroke (width 0.15) (type solid)) (layer "F.SilkS"))
    (fp_line (start -1.651 -1.651) (end 1.648 -1.651)
      (stroke (width 0.15) (type solid)) (layer "F.SilkS"))
    (fp_line (start -1.635 1.3) (end -1.635 1.634)
      (stroke (width 0.15) (type solid)) (layer "F.SilkS"))
    (fp_line (start -1.635 1.634) (end 1.634 1.634)
      (stroke (width 0.15) (type solid)) (layer "F.SilkS"))
    (fp_line (start 1.634 1.3) (end 1.634 1.634)
      (stroke (width 0.15) (type solid)) (layer "F.SilkS"))
    (fp_line (start 1.648 -1.651) (end 1.648 -1.317)
      (stroke (width 0.15) (type solid)) (layer "F.SilkS"))
    (fp_circle (center -1.9 -1.4) (end -1.85 -1.4)
      (stroke (width 0.15) (type solid)) (fill solid) (layer "F.SilkS"))
    (fp_rect (start -2 -1.8) (end 2 1.798)
      (stroke (width 0.05) (type solid)) (fill none) (layer "F.CrtYd"))
    (fp_line (start -1.6425 -1.4175) (end -1.4175 -1.6425)
      (stroke (width 0.15) (type solid)) (layer "F.Fab"))
    (fp_rect (start -1.651 -1.651) (end 1.648 1.648)
      (stroke (width 0.15) (type solid)) (fill none) (layer "F.Fab"))
    (pad "1" smd rect (at -1.436 -0.99 90) (size 0.99 0.405) (layers "F.Cu" "F.Paste" "F.Mask")
      (net 11 "VCC12V0") (pinfunction "S") (pintype "passive"))
    (pad "2" smd rect (at -1.436 -0.332 90) (size 0.99 0.405) (layers "F.Cu" "F.Paste" "F.Mask")
      (net 11 "VCC12V0") (pinfunction "S") (pintype "passive"))
    (pad "3" smd rect (at -1.436 0.33 90) (size 0.99 0.405) (layers "F.Cu" "F.Paste" "F.Mask")
      (net 11 "VCC12V0") (pinfunction "S") (pintype "passive"))
    (pad "4" smd rect (at -1.436 0.988 90) (size 0.99 0.405) (layers "F.Cu" "F.Paste" "F.Mask")
      (net 101 "Net-(QB3-G)") (pinfunction "G") (pintype "passive"))
    (pad "5" smd custom (at 0.557 0 90) (size 1.725 2.235) (layers "F.Cu" "F.Paste" "F.Mask")
      (net 28 "C_MEAS_3") (pinfunction "D") (pintype "passive") (zone_connect 2)
      (options (clearance outline) (anchor rect))
      (primitives
        (gr_poly
          (pts
            (xy 0.8625 0.1275)
            (xy 0.8625 -0.1275)
            (xy 1.3725 -0.1275)
            (xy 1.3725 -0.5325)
            (xy 0.8625 -0.5325)
            (xy 0.8625 -0.7875)
            (xy 1.3725 -0.7875)
            (xy 1.3725 -1.195)
            (xy 0.6125 -1.195)
            (xy 0.6125 1.195)
            (xy 1.3725 1.195)
            (xy 1.3725 0.7875)
            (xy 0.8625 0.7875)
            (xy 0.8625 0.5325)
            (xy 1.3725 0.5325)
            (xy 1.3725 0.1275)
          )
          (width 0) (fill yes))
      ))
  )
	(footprint "antmicro-footprints:TPD2E009DRTR" (layer "F.Cu")
    (at 181.1 103.25 180)
    (property "Author" "Antmicro")
    (property "License" "Apache-2.0")
    (property "MPN" "PESD5V0S2BQA")
    (property "Manufacturer" "Nexperia")
    (property "Sheetfile" "d1600e-psu-breakout-board.kicad_sch")
    (property "Sheetname" "")
    (property "ki_description" "TVS diode array, 30 kV, SOT-1215, 5V, 45 pF")
    (property "ki_keywords" "SMT, DIODE, SEMICONDUCTOR, TVS, ESD")
    (attr smd)
    (fp_text reference "D12" (at -0.76 1.22) (layer "F.SilkS")
        (effects (font (size 0.7 0.7) (thickness 0.15)))
    )
    (fp_text value "PESD5V0S2BQA" (at 5.6088 1.3064) (layer "F.Fab") hide
        (effects (font (size 0.64 0.64) (thickness 0.015)))
    )
    (fp_text user "License: Apache-2.0" (at -0.949 5.706 180) (layer "F.Fab") hide
        (effects (font (size 0.7 0.7) (thickness 0.15)) (justify left bottom))
    )
    (fp_text user "${REFERENCE}" (at -0.949 4.506 180) (layer "F.Fab") hide
        (effects (font (size 0.7 0.7) (thickness 0.15)) (justify left bottom))
    )
    (fp_text user "Author: Antmicro" (at -0.949 3.306 180) (layer "F.Fab") hide
        (effects (font (size 0.7 0.7) (thickness 0.15)) (justify left bottom))
    )
    (fp_line (start 0.03 -0.499) (end 0.4 -0.499)
      (stroke (width 0.15) (type solid)) (layer "F.SilkS"))
    (fp_line (start 0.03 0.499) (end 0.4 0.499)
      (stroke (width 0.15) (type solid)) (layer "F.SilkS"))
    (fp_line (start 0.4 -0.419) (end 0.4 -0.499)
      (stroke (width 0.15) (type solid)) (layer "F.SilkS"))
    (fp_line (start 0.4 0.42) (end 0.4 0.499)
      (stroke (width 0.15) (type solid)) (layer "F.SilkS"))
    (fp_circle (center -0.5 -0.6) (end -0.45 -0.6)
      (stroke (width 0.15) (type solid)) (fill solid) (layer "F.SilkS"))
    (fp_rect (start -0.8 -0.59) (end 0.8 0.59)
      (stroke (width 0.05) (type solid)) (fill none) (layer "F.CrtYd"))
    (fp_line (start -0.4 -0.499) (end 0.4 -0.499)
      (stroke (width 0.15) (type solid)) (layer "F.Fab"))
    (fp_line (start -0.4 0.499) (end -0.4 -0.499)
      (stroke (width 0.15) (type solid)) (layer "F.Fab"))
    (fp_line (start 0.4 -0.499) (end 0.4 0.499)
      (stroke (width 0.15) (type solid)) (layer "F.Fab"))
    (fp_line (start 0.4 0.499) (end -0.4 0.499)
      (stroke (width 0.15) (type solid)) (layer "F.Fab"))
    (pad "1" smd rect (at -0.52 -0.349 180) (size 0.46 0.2) (layers "F.Cu" "F.Paste" "F.Mask")
      (net 17 "SCL") (pinfunction "IO1") (pintype "passive"))
    (pad "2" smd rect (at -0.52 0.348 180) (size 0.46 0.2) (layers "F.Cu" "F.Paste" "F.Mask")
      (net 99 "SDA_CON") (pinfunction "IO2") (pintype "passive"))
    (pad "3" smd rect (at 0.52 0 180) (size 0.46 0.2) (layers "F.Cu" "F.Paste" "F.Mask")
      (net 4 "GND") (pinfunction "GND") (pintype "passive"))
  )
	(footprint "antmicro-footprints:R_0402_1005Metric" (layer "F.Cu")
    (at 142.2 96.6 180)
    (descr "Resistor SMD 0402")
    (tags "resistor SMD 0402")
    (property "Author" "Antmicro")
    (property "License" "Apache-2.0")
    (property "MPN" "RC0402BR-07100KL")
    (property "Manufacturer" "Yageo")
    (property "Sheetfile" "pow-cycl-curr-meas.kicad_sch")
    (property "Sheetname" "Power Cycling & Current Measurement")
    (property "Tolerance" "0.1%")
    (property "Val" "100k")
    (property "ki_description" "SMD Chip Resistor, 100 kohm, ± 0.1%, 63 mW, 0402 [1005 Metric], Thin Film")
    (property "ki_keywords" "0402, SMT, RESISTOR, PASSIVE")
    (attr smd)
    (fp_text reference "R2" (at 3 -0.45 180) (layer "F.SilkS")
        (effects (font (size 0.7 0.7) (thickness 0.15)) (justify left bottom))
    )
    (fp_text value "R_100k_0.1%_0402" (at -1.011843 1.772047 180) (layer "F.Fab")
        (effects (font (size 0.7 0.7) (thickness 0.15)) (justify left bottom))
    )
    (fp_text user "Author: Antmicro" (at -0.95 4.169 180) (layer "F.Fab") hide
        (effects (font (size 0.7 0.7) (thickness 0.15)) (justify left bottom))
    )
    (fp_text user "${REFERENCE}" (at -0.95 3.168 180) (layer "F.Fab") hide
        (effects (font (size 0.7 0.7) (thickness 0.15)) (justify left bottom))
    )
    (fp_text user "License: Apache-2.0" (at -0.95 5.169 180) (layer "F.Fab") hide
        (effects (font (size 0.7 0.7) (thickness 0.15)) (justify left bottom))
    )
    (fp_rect (start -0.925 -0.47) (end 0.925 0.47)
      (stroke (width 0.05) (type default)) (fill none) (layer "F.CrtYd"))
    (fp_rect (start -0.5 -0.25) (end 0.5 0.25)
      (stroke (width 0.15) (type solid)) (fill none) (layer "F.Fab"))
    (pad "1" smd roundrect (at -0.48 0 180) (size 0.59 0.64) (layers "F.Cu" "F.Paste" "F.Mask") (roundrect_rratio 0.25)
      (net 144 "Net-(R2-Pad1)") (pintype "passive"))
    (pad "2" smd roundrect (at 0.48 0 180) (size 0.59 0.64) (layers "F.Cu" "F.Paste" "F.Mask") (roundrect_rratio 0.25)
      (net 11 "VCC12V0") (pintype "passive"))
  )
	(footprint "antmicro-footprints:R_0402_1005Metric" (layer "F.Cu")
    (at 128.9 89.4 180)
    (descr "Resistor SMD 0402")
    (tags "resistor SMD 0402")
    (property "Author" "Antmicro")
    (property "DNP" "DNP")
    (property "License" "Apache-2.0")
    (property "MPN" "CR0402-FX-1002GLF")
    (property "Manufacturer" "Bourns")
    (property "Sheetfile" "power-switch.kicad_sch")
    (property "Sheetname" "Power switch 2")
    (property "Tolerance" "1%")
    (property "Val" "10k")
    (property "dnp" "")
    (property "exclude_from_bom" "")
    (property "ki_description" "SMD Chip Resistor, 10 kohm, ± 1%, 62.5 mW, 0402 [1005 Metric], Thick Film, General Purpose")
    (property "ki_keywords" "0402, SMT, RESISTOR, PASSIVE")
    (attr smd exclude_from_bom)
    (fp_text reference "R47" (at 3.15 -0.45 180) (layer "F.SilkS")
        (effects (font (size 0.7 0.7) (thickness 0.15)) (justify left bottom))
    )
    (fp_text value "R_10k_0402" (at -1.011843 1.772047 180) (layer "F.Fab")
        (effects (font (size 0.7 0.7) (thickness 0.15)) (justify left bottom))
    )
    (fp_text user "License: Apache-2.0" (at -0.95 5.169 180) (layer "F.Fab") hide
        (effects (font (size 0.7 0.7) (thickness 0.15)) (justify left bottom))
    )
    (fp_text user "${REFERENCE}" (at -0.95 3.168 180) (layer "F.Fab") hide
        (effects (font (size 0.7 0.7) (thickness 0.15)) (justify left bottom))
    )
    (fp_text user "Author: Antmicro" (at -0.95 4.169 180) (layer "F.Fab") hide
        (effects (font (size 0.7 0.7) (thickness 0.15)) (justify left bottom))
    )
    (fp_rect (start -0.925 -0.47) (end 0.925 0.47)
      (stroke (width 0.05) (type default)) (fill none) (layer "F.CrtYd"))
    (fp_rect (start -0.5 -0.25) (end 0.5 0.25)
      (stroke (width 0.15) (type solid)) (fill none) (layer "F.Fab"))
    (pad "1" smd roundrect (at -0.48 0 180) (size 0.59 0.64) (layers "F.Cu" "F.Paste" "F.Mask") (roundrect_rratio 0.25)
      (net 24 "/Power Cycling & Current Measurement/PC_2") (pintype "passive"))
    (pad "2" smd roundrect (at 0.48 0 180) (size 0.59 0.64) (layers "F.Cu" "F.Paste" "F.Mask") (roundrect_rratio 0.25)
      (net 4 "GND") (pintype "passive"))
  )
	(footprint "antmicro-footprints:R_0402_1005Metric" (layer "F.Cu")
    (at 172.1 91.7 -90)
    (descr "Resistor SMD 0402")
    (tags "resistor SMD 0402")
    (property "Author" "Antmicro")
    (property "License" "Apache-2.0")
    (property "MPN" "CR0402-FX-2R00GLF")
    (property "Manufacturer" "Bourns")
    (property "Sheetfile" "power-switch.kicad_sch")
    (property "Sheetname" "Power switch 4")
    (property "Tolerance" "1%")
    (property "Val" "2R")
    (property "ki_description" "SMD Chip Resistor")
    (property "ki_keywords" "0402, SMT, RESISTOR, PASSIVE")
    (attr smd)
    (fp_text reference "R64" (at 1.35 -0.35) (layer "F.SilkS")
        (effects (font (size 0.7 0.7) (thickness 0.15)) (justify left bottom))
    )
    (fp_text value "R_2R_0402" (at -1.011843 1.772047 -90) (layer "F.Fab")
        (effects (font (size 0.7 0.7) (thickness 0.15)) (justify left bottom))
    )
    (fp_text user "License: Apache-2.0" (at -0.95 5.169 -90) (layer "F.Fab") hide
        (effects (font (size 0.7 0.7) (thickness 0.15)) (justify left bottom))
    )
    (fp_text user "${REFERENCE}" (at -0.95 3.168 -90) (layer "F.Fab") hide
        (effects (font (size 0.7 0.7) (thickness 0.15)) (justify left bottom))
    )
    (fp_text user "Author: Antmicro" (at -0.95 4.169 -90) (layer "F.Fab") hide
        (effects (font (size 0.7 0.7) (thickness 0.15)) (justify left bottom))
    )
    (fp_rect (start -0.925 -0.47) (end 0.925 0.47)
      (stroke (width 0.05) (type default)) (fill none) (layer "F.CrtYd"))
    (fp_rect (start -0.5 -0.25) (end 0.5 0.25)
      (stroke (width 0.15) (type solid)) (fill none) (layer "F.Fab"))
    (pad "1" smd roundrect (at -0.48 0 270) (size 0.59 0.64) (layers "F.Cu" "F.Paste" "F.Mask") (roundrect_rratio 0.25)
      (net 102 "Net-(QB4-G)") (pintype "passive"))
    (pad "2" smd roundrect (at 0.48 0 270) (size 0.59 0.64) (layers "F.Cu" "F.Paste" "F.Mask") (roundrect_rratio 0.25)
      (net 85 "Net-(D17-A)") (pintype "passive"))
  )
)
